# T6G (Grand Teton) — schematic netlist excerpt (pin names and nets, part order shuffled) for the footprints in the layout excerpt that follows; sources: Cadence DE-HDL packaged netlist, KiCad conversion of 04192023_DAF0TMB3IC0_F0TG_MB_C_brd_V02_OCP.brd

C7009  Q_CAPP  470UF 2.5V 20% SPCAP  pkg SMLF  page 279 : A = P0V9_CPU0_RT0_2A ; B = GND
C1839  Q_CAP  0.1UF 25V 10% X7R  pkg 0402  page 137 : A = P12V_OCP_V3_2_R ; B = GND

(kicad_pcb
	(version 20260206)
	(generator "pcbnew")
	(generator_version "10.0")
	(general
		(thickness 1.6)
		(legacy_teardrops no)
	)
	(paper "A4")
	(title_block
		(title "04192023_DAF0TMB3IC0_F0TG_MB_C_brd_V02_OCP.brd")
		(comment 1 "Grand Teton / footprints 6970-6972 of 8354")
	)
	(layers
		(0 "F.Cu" signal "TOP")
		(4 "In1.Cu" signal "GND")
		(6 "In2.Cu" signal "IN1")
		(8 "In3.Cu" signal "GND1")
		(10 "In4.Cu" signal "IN2")
		(12 "In5.Cu" signal "GND2")
		(14 "In6.Cu" signal "IN3")
		(16 "In7.Cu" signal "GND3")
		(18 "In8.Cu" signal "VCC")
		(20 "In9.Cu" signal "VCC1")
		(22 "In10.Cu" signal "GND4")
		(24 "In11.Cu" signal "IN4")
		(26 "In12.Cu" signal "GND5")
		(28 "In13.Cu" signal "IN5")
		(30 "In14.Cu" signal "GND6")
		(32 "In15.Cu" signal "IN6")
		(34 "In16.Cu" signal "GND7")
		(2 "B.Cu" signal "BOTTOM")
		(9 "F.Adhes" user "F.Adhesive")
		(11 "B.Adhes" user "B.Adhesive")
		(13 "F.Paste" user "Package Geometry/Pastemask Top")
		(15 "B.Paste" user "Package Geometry/Pastemask Bottom")
		(5 "F.SilkS" user "Ref Des/Silkscreen Top")
		(7 "B.SilkS" user "Ref Des/Silkscreen Bottom")
		(1 "F.Mask" user "Board Geometry/Soldermask Top")
		(3 "B.Mask" user "Board Geometry/Soldermask Bottom")
		(17 "Dwgs.User" user "User.Drawings")
		(19 "Cmts.User" user "User.Comments")
		(21 "Eco1.User" user "User.Eco1")
		(23 "Eco2.User" user "User.Eco2")
		(25 "Edge.Cuts" user "Board Geometry/Outline")
		(27 "Margin" user)
		(31 "F.CrtYd" user "Package Geometry/Place Bound Top")
		(29 "B.CrtYd" user "Package Geometry/Place Bound Bottom")
		(35 "F.Fab" user "Ref Des/Assembly Top")
		(33 "B.Fab" user "Ref Des/Assembly Bottom")
	)
	(footprint ""
		(layer "B.Cu")
		(at 65.3796 -14.8336)
		(property "Reference" "C1839"
			(at 0 0 0)
			(layer "B.SilkS")
			(hide yes)
			(effects
				(font
					(size 1.27 1.27)
				)
				(justify mirror)
			)
		)
		(property "Value" ""
			(at 0 0 0)
			(layer "B.Fab")
			(effects
				(font
					(size 1.27 1.27)
				)
				(justify mirror)
			)
		)
		(duplicate_pad_numbers_are_jumpers no)
		(fp_line
			(start -0.7874 -0.4064)
			(end -0.7874 0.4064)
			(stroke
				(width 0.1524)
				(type default)
			)
			(layer "B.SilkS")
		)
		(fp_line
			(start -0.7874 0.4064)
			(end 0.7874 0.4064)
			(stroke
				(width 0.1524)
				(type default)
			)
			(layer "B.SilkS")
		)
		(fp_line
			(start 0.7874 -0.4064)
			(end -0.7874 -0.4064)
			(stroke
				(width 0.1524)
				(type default)
			)
			(layer "B.SilkS")
		)
		(fp_line
			(start 0.7874 0.4064)
			(end 0.7874 -0.4064)
			(stroke
				(width 0.1524)
				(type default)
			)
			(layer "B.SilkS")
		)
		(fp_line
			(start -0.67945 -0.3048)
			(end -0.67945 0.3048)
			(stroke
				(width 0.1)
				(type default)
			)
			(layer "B.Fab")
		)
		(fp_line
			(start -0.67945 0.3048)
			(end -0.120396 0.3048)
			(stroke
				(width 0.1)
				(type default)
			)
			(layer "B.Fab")
		)
		(fp_line
			(start -0.12065 -0.3048)
			(end -0.67945 -0.3048)
			(stroke
				(width 0.1)
				(type default)
			)
			(layer "B.Fab")
		)
		(fp_line
			(start -0.12065 -0.2794)
			(end -0.12065 -0.3048)
			(stroke
				(width 0.1)
				(type default)
			)
			(layer "B.Fab")
		)
		(fp_line
			(start -0.120396 0.2794)
			(end 0.12065 0.2794)
			(stroke
				(width 0.1)
				(type default)
			)
			(layer "B.Fab")
		)
		(fp_line
			(start -0.120396 0.3048)
			(end -0.120396 0.2794)
			(stroke
				(width 0.1)
				(type default)
			)
			(layer "B.Fab")
		)
		(fp_line
			(start 0.12065 -0.305054)
			(end 0.12065 -0.2794)
			(stroke
				(width 0.1)
				(type default)
			)
			(layer "B.Fab")
		)
		(fp_line
			(start 0.12065 -0.2794)
			(end -0.12065 -0.2794)
			(stroke
				(width 0.1)
				(type default)
			)
			(layer "B.Fab")
		)
		(fp_line
			(start 0.12065 0.2794)
			(end 0.12065 0.3048)
			(stroke
				(width 0.1)
				(type default)
			)
			(layer "B.Fab")
		)
		(fp_line
			(start 0.12065 0.3048)
			(end 0.67945 0.3048)
			(stroke
				(width 0.1)
				(type default)
			)
			(layer "B.Fab")
		)
		(fp_line
			(start 0.67945 -0.305054)
			(end 0.12065 -0.305054)
			(stroke
				(width 0.1)
				(type default)
			)
			(layer "B.Fab")
		)
		(fp_line
			(start 0.67945 0.3048)
			(end 0.67945 -0.305054)
			(stroke
				(width 0.1)
				(type default)
			)
			(layer "B.Fab")
		)
		(pad "1" smd circle
			(at 0.40005 0 180)
			(size 0 0)
			(layers "B.Cu" "B.Mask" "B.Paste")
			(net "P12V_OCP_V3_2_R")
		)
		(pad "2" smd circle
			(at -0.40005 0 180)
			(size 0 0)
			(layers "B.Cu" "B.Mask" "B.Paste")
			(net "GND")
		)
	)
	(footprint ""
		(layer "B.Cu")
		(at 433.05222 -418.942266 180)
		(property "Reference" ""
			(at 0 0 0)
			(layer "B.SilkS")
			(hide yes)
			(effects
				(font
					(size 1.27 1.27)
				)
				(justify mirror)
			)
		)
		(property "Value" ""
			(at 0 0 0)
			(layer "B.Fab")
			(effects
				(font
					(size 1.27 1.27)
				)
				(justify mirror)
			)
		)
		(duplicate_pad_numbers_are_jumpers no)
		(pad "1" smd circle
			(at 0 0)
			(size 0.9906 0.9906)
			(layers "B.Cu" "B.Mask" "B.Paste")
			(net "Net_655")
		)
		(zone
			(layer "B.Cu")
			(hatch none 0.5)
			(connect_pads
				(clearance 0)
			)
			(min_thickness 0.25)
			(keepout
				(tracks not_allowed)
				(vias allowed)
				(pads allowed)
				(copperpour not_allowed)
				(footprints allowed)
			)
			(placement
				(enabled no)
				(sheetname "")
			)
			(fill
				(thermal_gap 0.5)
				(thermal_bridge_width 0.5)
				(island_removal_mode 0)
			)
			(polygon
				(pts
					(arc
						(start 434.67782 -418.942266)
						(mid 431.42662 -418.942266)
						(end 434.67782 -418.942266)
					)
				)
			)
		)
	)
	(footprint ""
		(layer "B.Cu")
		(at 317.967614 -389.49503)
		(property "Reference" "C7009"
			(at 3.4925 3.131312 0)
			(unlocked yes)
			(layer "B.SilkS")
			(effects
				(font
					(size 0.7874 0.5842)
					(thickness 0.1524)
				)
				(justify left mirror)
			)
		)
		(property "Value" ""
			(at 0 0 0)
			(layer "B.Fab")
			(effects
				(font
					(size 1.27 1.27)
				)
				(justify mirror)
			)
		)
		(duplicate_pad_numbers_are_jumpers no)
		(fp_line
			(start -4.53898 -2.15011)
			(end -4.53898 2.15011)
			(stroke
				(width 0.1524)
				(type default)
			)
			(layer "B.SilkS")
		)
		(fp_line
			(start -4.53898 2.15011)
			(end 4.53898 2.15011)
			(stroke
				(width 0.1524)
				(type default)
			)
			(layer "B.SilkS")
		)
		(fp_line
			(start 4.53898 -2.150618)
			(end 4.539742 2.152142)
			(stroke
				(width 0.1524)
				(type default)
			)
			(layer "B.SilkS")
		)
		(fp_line
			(start 4.53898 -2.15011)
			(end -4.53898 -2.15011)
			(stroke
				(width 0.1524)
				(type default)
			)
			(layer "B.SilkS")
		)
		(fp_line
			(start 4.53898 2.15011)
			(end 4.53898 -2.15011)
			(stroke
				(width 0.1524)
				(type default)
			)
			(layer "B.SilkS")
		)
		(fp_line
			(start 4.69138 -2.150618)
			(end 4.692396 2.161032)
			(stroke
				(width 0.1524)
				(type default)
			)
			(layer "B.SilkS")
		)
		(fp_line
			(start 4.83108 2.150364)
			(end 4.447794 2.149348)
			(stroke
				(width 0.1524)
				(type default)
			)
			(layer "B.SilkS")
		)
		(fp_line
			(start 4.84378 -2.150618)
			(end 4.53898 -2.150618)
			(stroke
				(width 0.1524)
				(type default)
			)
			(layer "B.SilkS")
		)
		(fp_line
			(start 4.84378 -2.150618)
			(end 4.842256 2.163064)
			(stroke
				(width 0.1524)
				(type default)
			)
			(layer "B.SilkS")
		)
		(fp_line
			(start -3.64998 -2.15011)
			(end -3.64998 2.15011)
			(stroke
				(width 0.1)
				(type default)
			)
			(layer "B.Fab")
		)
		(fp_line
			(start -3.64998 2.15011)
			(end 3.64998 2.15011)
			(stroke
				(width 0.1)
				(type default)
			)
			(layer "B.Fab")
		)
		(fp_line
			(start 3.64998 -2.15011)
			(end -3.64998 -2.15011)
			(stroke
				(width 0.1)
				(type default)
			)
			(layer "B.Fab")
		)
		(fp_line
			(start 3.64998 2.15011)
			(end 3.64998 -2.15011)
			(stroke
				(width 0.1)
				(type default)
			)
			(layer "B.Fab")
		)
		(fp_text user "-"
			(at -3.109214 2.382012 0)
			(unlocked yes)
			(layer "B.SilkS")
			(effects
				(font
					(size 1.905 1.4224)
					(thickness 0.1524)
				)
				(justify left mirror)
			)
		)
		(fp_text user "+"
			(at 6.214872 -0.337058 0)
			(unlocked yes)
			(layer "B.SilkS")
			(effects
				(font
					(size 1.905 1.4224)
					(thickness 0.1524)
				)
				(justify left mirror)
			)
		)
		(fp_text user "-"
			(at -4.313174 -0.094488 0)
			(unlocked yes)
			(layer "B.Fab")
			(effects
				(font
					(size 1.905 1.4224)
					(thickness 0.1524)
				)
				(justify left mirror)
			)
		)
		(fp_text user "+"
			(at 6.214872 -0.337058 0)
			(unlocked yes)
			(layer "B.Fab")
			(effects
				(font
					(size 1.905 1.4224)
					(thickness 0.1524)
				)
				(justify left mirror)
			)
		)
		(pad "1" smd rect
			(at 3.199892 0 180)
			(size 2.413 2.8194)
			(layers "B.Cu" "B.Mask" "B.Paste")
			(net "P0V9_CPU0_RT0_2A")
		)
		(pad "2" smd rect
			(at -3.199892 0 180)
			(size 2.413 2.8194)
			(layers "B.Cu" "B.Mask" "B.Paste")
			(net "GND")
		)
	)
)
